G04 ================== begin FILE IDENTIFICATION RECORD ==================*
G04 Layout Name:  15750-1.brd*
G04 Film Name:    BMASK*
G04 File Format:  Gerber RS274X*
G04 File Origin:  Cadence Allegro 16.5-S056*
G04 Origin Date:  Fri Dec 30 13:21:27 2016*
G04 *
G04 Layer:  VIA CLASS/SOLDERMASK_BOTTOM*
G04 Layer:  PIN/SOLDERMASK_BOTTOM*
G04 Layer:  PACKAGE GEOMETRY/SOLDERMASK_BOTTOM*
G04 Layer:  DRAWING FORMAT/LAYER_PCB_STORY*
G04 Layer:  DRAWING FORMAT/LAYER_SOLDER_B*
G04 Layer:  BOARD GEOMETRY/SOLDERMASK_BOTTOM*
G04 *
G04 Offset:    (0.00 0.00)*
G04 Mirror:    No*
G04 Mode:      Positive*
G04 Rotation:  0*
G04 FullContactRelief:  No*
G04 UndefLineWidth:     6.00*
G04 ================== end FILE IDENTIFICATION RECORD ====================*
%FSLAX35Y35*MOIN*%
%IR0*IPPOS*OFA0.00000B0.00000*MIA0B0*SFA1.00000B1.00000*%
%AMMACRO17*
4,1,40,.011,.007,
.011,-.007,
.010939,-.007695,
.010759,-.008368,
.010464,-.009,
.010064,-.009571,
.009571,-.010064,
.009,-.010464,
.008368,-.010759,
.007695,-.010939,
.007,-.011,
-.007,-.011,
-.007695,-.010939,
-.008368,-.010759,
-.009,-.010464,
-.009571,-.010064,
-.010064,-.009571,
-.010464,-.009,
-.010759,-.008368,
-.010939,-.007695,
-.011,-.007,
-.011,.007,
-.010939,.007695,
-.010759,.008368,
-.010464,.009,
-.010064,.009571,
-.009571,.010064,
-.009,.010464,
-.008368,.010759,
-.007695,.010939,
-.007,.011,
.007,.011,
.007695,.010939,
.008368,.010759,
.009,.010464,
.009571,.010064,
.010064,.009571,
.010464,.009,
.010759,.008368,
.010939,.007695,
.011,.007,
0.0*
%
%ADD17MACRO17*%
%AMMACRO24*
4,1,40,.013,-.017,
-.013,-.017,
-.013695,-.016939,
-.014368,-.016759,
-.015,-.016464,
-.015571,-.016064,
-.016064,-.015571,
-.016464,-.015,
-.016759,-.014368,
-.016939,-.013695,
-.017,-.013,
-.017,.013,
-.016939,.013695,
-.016759,.014368,
-.016464,.015,
-.016064,.015571,
-.015571,.016064,
-.015,.016464,
-.014368,.016759,
-.013695,.016939,
-.013,.017,
.013,.017,
.013695,.016939,
.014368,.016759,
.015,.016464,
.015571,.016064,
.016064,.015571,
.016464,.015,
.016759,.014368,
.016939,.013695,
.017,.013,
.017,-.013,
.016939,-.013695,
.016759,-.014368,
.016464,-.015,
.016064,-.015571,
.015571,-.016064,
.015,-.016464,
.014368,-.016759,
.013695,-.016939,
.013,-.017,
0.0*
%
%ADD24MACRO24*%
%ADD32C,.044*%
%ADD12C,.08*%
%ADD31C,.063*%
%ADD13C,.028*%
%ADD38C,.065*%
%ADD35C,.056*%
%ADD10C,.086*%
%AMMACRO18*
4,1,40,.007,-.011,
-.007,-.011,
-.007695,-.010939,
-.008368,-.010759,
-.009,-.010464,
-.009571,-.010064,
-.010064,-.009571,
-.010464,-.009,
-.010759,-.008368,
-.010939,-.007695,
-.011,-.007,
-.011,.007,
-.010939,.007695,
-.010759,.008368,
-.010464,.009,
-.010064,.009571,
-.009571,.010064,
-.009,.010464,
-.008368,.010759,
-.007695,.010939,
-.007,.011,
.007,.011,
.007695,.010939,
.008368,.010759,
.009,.010464,
.009571,.010064,
.010064,.009571,
.010464,.009,
.010759,.008368,
.010939,.007695,
.011,.007,
.011,-.007,
.010939,-.007695,
.010759,-.008368,
.010464,-.009,
.010064,-.009571,
.009571,-.010064,
.009,-.010464,
.008368,-.010759,
.007695,-.010939,
.007,-.011,
0.0*
%
%ADD18MACRO18*%
%AMMACRO14*
4,1,40,-.011,-.007,
-.011,.007,
-.010939,.007695,
-.010759,.008368,
-.010464,.009,
-.010064,.009571,
-.009571,.010064,
-.009,.010464,
-.008368,.010759,
-.007695,.010939,
-.007,.011,
.007,.011,
.007695,.010939,
.008368,.010759,
.009,.010464,
.009571,.010064,
.010064,.009571,
.010464,.009,
.010759,.008368,
.010939,.007695,
.011,.007,
.011,-.007,
.010939,-.007695,
.010759,-.008368,
.010464,-.009,
.010064,-.009571,
.009571,-.010064,
.009,-.010464,
.008368,-.010759,
.007695,-.010939,
.007,-.011,
-.007,-.011,
-.007695,-.010939,
-.008368,-.010759,
-.009,-.010464,
-.009571,-.010064,
-.010064,-.009571,
-.010464,-.009,
-.010759,-.008368,
-.010939,-.007695,
-.011,-.007,
0.0*
%
%ADD14MACRO14*%
%AMMACRO26*
4,1,40,-.008,.012,
.008,.012,
.008695,.011939,
.009368,.011759,
.01,.011464,
.010571,.011064,
.011064,.010571,
.011464,.01,
.011759,.009368,
.011939,.008695,
.012,.008,
.012,-.008,
.011939,-.008695,
.011759,-.009368,
.011464,-.01,
.011064,-.010571,
.010571,-.011064,
.01,-.011464,
.009368,-.011759,
.008695,-.011939,
.008,-.012,
-.008,-.012,
-.008695,-.011939,
-.009368,-.011759,
-.01,-.011464,
-.010571,-.011064,
-.011064,-.010571,
-.011464,-.01,
-.011759,-.009368,
-.011939,-.008695,
-.012,-.008,
-.012,.008,
-.011939,.008695,
-.011759,.009368,
-.011464,.01,
-.011064,.010571,
-.010571,.011064,
-.01,.011464,
-.009368,.011759,
-.008695,.011939,
-.008,.012,
0.0*
%
%ADD26MACRO26*%
%AMMACRO27*
4,1,40,-.013,.017,
.013,.017,
.013695,.016939,
.014368,.016759,
.015,.016464,
.015571,.016064,
.016064,.015571,
.016464,.015,
.016759,.014368,
.016939,.013695,
.017,.013,
.017,-.013,
.016939,-.013695,
.016759,-.014368,
.016464,-.015,
.016064,-.015571,
.015571,-.016064,
.015,-.016464,
.014368,-.016759,
.013695,-.016939,
.013,-.017,
-.013,-.017,
-.013695,-.016939,
-.014368,-.016759,
-.015,-.016464,
-.015571,-.016064,
-.016064,-.015571,
-.016464,-.015,
-.016759,-.014368,
-.016939,-.013695,
-.017,-.013,
-.017,.013,
-.016939,.013695,
-.016759,.014368,
-.016464,.015,
-.016064,.015571,
-.015571,.016064,
-.015,.016464,
-.014368,.016759,
-.013695,.016939,
-.013,.017,
0.0*
%
%ADD27MACRO27*%
%AMMACRO19*
4,1,40,.007,-.011,
-.007,-.011,
-.007695,-.010939,
-.008368,-.010759,
-.009,-.010464,
-.009571,-.010064,
-.010064,-.009571,
-.010464,-.009,
-.010759,-.008368,
-.010939,-.007695,
-.011,-.007,
-.011,.007,
-.010939,.007695,
-.010759,.008368,
-.010464,.009,
-.010064,.009571,
-.009571,.010064,
-.009,.010464,
-.008368,.010759,
-.007695,.010939,
-.007,.011,
.007,.011,
.007695,.010939,
.008368,.010759,
.009,.010464,
.009571,.010064,
.010064,.009571,
.010464,.009,
.010759,.008368,
.010939,.007695,
.011,.007,
.011,-.007,
.010939,-.007695,
.010759,-.008368,
.010464,-.009,
.010064,-.009571,
.009571,-.010064,
.009,-.010464,
.008368,-.010759,
.007695,-.010939,
.007,-.011,
0.0*
%
%ADD19MACRO19*%
%AMMACRO15*
4,1,40,-.011,-.007,
-.011,.007,
-.010939,.007695,
-.010759,.008368,
-.010464,.009,
-.010064,.009571,
-.009571,.010064,
-.009,.010464,
-.008368,.010759,
-.007695,.010939,
-.007,.011,
.007,.011,
.007695,.010939,
.008368,.010759,
.009,.010464,
.009571,.010064,
.010064,.009571,
.010464,.009,
.010759,.008368,
.010939,.007695,
.011,.007,
.011,-.007,
.010939,-.007695,
.010759,-.008368,
.010464,-.009,
.010064,-.009571,
.009571,-.010064,
.009,-.010464,
.008368,-.010759,
.007695,-.010939,
.007,-.011,
-.007,-.011,
-.007695,-.010939,
-.008368,-.010759,
-.009,-.010464,
-.009571,-.010064,
-.010064,-.009571,
-.010464,-.009,
-.010759,-.008368,
-.010939,-.007695,
-.011,-.007,
0.0*
%
%ADD15MACRO15*%
%AMMACRO25*
4,1,40,-.008,.012,
.008,.012,
.008695,.011939,
.009368,.011759,
.01,.011464,
.010571,.011064,
.011064,.010571,
.011464,.01,
.011759,.009368,
.011939,.008695,
.012,.008,
.012,-.008,
.011939,-.008695,
.011759,-.009368,
.011464,-.01,
.011064,-.010571,
.010571,-.011064,
.01,-.011464,
.009368,-.011759,
.008695,-.011939,
.008,-.012,
-.008,-.012,
-.008695,-.011939,
-.009368,-.011759,
-.01,-.011464,
-.010571,-.011064,
-.011064,-.010571,
-.011464,-.01,
-.011759,-.009368,
-.011939,-.008695,
-.012,-.008,
-.012,.008,
-.011939,.008695,
-.011759,.009368,
-.011464,.01,
-.011064,.010571,
-.010571,.011064,
-.01,.011464,
-.009368,.011759,
-.008695,.011939,
-.008,.012,
0.0*
%
%ADD25MACRO25*%
%AMMACRO28*
4,1,40,-.013,.017,
.013,.017,
.013695,.016939,
.014368,.016759,
.015,.016464,
.015571,.016064,
.016064,.015571,
.016464,.015,
.016759,.014368,
.016939,.013695,
.017,.013,
.017,-.013,
.016939,-.013695,
.016759,-.014368,
.016464,-.015,
.016064,-.015571,
.015571,-.016064,
.015,-.016464,
.014368,-.016759,
.013695,-.016939,
.013,-.017,
-.013,-.017,
-.013695,-.016939,
-.014368,-.016759,
-.015,-.016464,
-.015571,-.016064,
-.016064,-.015571,
-.016464,-.015,
-.016759,-.014368,
-.016939,-.013695,
-.017,-.013,
-.017,.013,
-.016939,.013695,
-.016759,.014368,
-.016464,.015,
-.016064,.015571,
-.015571,.016064,
-.015,.016464,
-.014368,.016759,
-.013695,.016939,
-.013,.017,
0.0*
%
%ADD28MACRO28*%
%ADD39R,.157X.15*%
%ADD36R,.069X.02*%
%ADD37R,.073X.035*%
%ADD11C,.315*%
%ADD29R,.045X.055*%
%ADD33R,.016X.048*%
%ADD22R,.055X.045*%
%AMMACRO30*
4,1,40,.012,.008,
.012,-.008,
.011939,-.008695,
.011759,-.009368,
.011464,-.01,
.011064,-.010571,
.010571,-.011064,
.01,-.011464,
.009368,-.011759,
.008695,-.011939,
.008,-.012,
-.008,-.012,
-.008695,-.011939,
-.009368,-.011759,
-.01,-.011464,
-.010571,-.011064,
-.011064,-.010571,
-.011464,-.01,
-.011759,-.009368,
-.011939,-.008695,
-.012,-.008,
-.012,.008,
-.011939,.008695,
-.011759,.009368,
-.011464,.01,
-.011064,.010571,
-.010571,.011064,
-.01,.011464,
-.009368,.011759,
-.008695,.011939,
-.008,.012,
.008,.012,
.008695,.011939,
.009368,.011759,
.01,.011464,
.010571,.011064,
.011064,.010571,
.011464,.01,
.011759,.009368,
.011939,.008695,
.012,.008,
0.0*
%
%ADD30MACRO30*%
%AMMACRO20*
4,1,40,-.007,.011,
.007,.011,
.007695,.010939,
.008368,.010759,
.009,.010464,
.009571,.010064,
.010064,.009571,
.010464,.009,
.010759,.008368,
.010939,.007695,
.011,.007,
.011,-.007,
.010939,-.007695,
.010759,-.008368,
.010464,-.009,
.010064,-.009571,
.009571,-.010064,
.009,-.010464,
.008368,-.010759,
.007695,-.010939,
.007,-.011,
-.007,-.011,
-.007695,-.010939,
-.008368,-.010759,
-.009,-.010464,
-.009571,-.010064,
-.010064,-.009571,
-.010464,-.009,
-.010759,-.008368,
-.010939,-.007695,
-.011,-.007,
-.011,.007,
-.010939,.007695,
-.010759,.008368,
-.010464,.009,
-.010064,.009571,
-.009571,.010064,
-.009,.010464,
-.008368,.010759,
-.007695,.010939,
-.007,.011,
0.0*
%
%ADD20MACRO20*%
%AMMACRO16*
4,1,40,.011,.007,
.011,-.007,
.010939,-.007695,
.010759,-.008368,
.010464,-.009,
.010064,-.009571,
.009571,-.010064,
.009,-.010464,
.008368,-.010759,
.007695,-.010939,
.007,-.011,
-.007,-.011,
-.007695,-.010939,
-.008368,-.010759,
-.009,-.010464,
-.009571,-.010064,
-.010064,-.009571,
-.010464,-.009,
-.010759,-.008368,
-.010939,-.007695,
-.011,-.007,
-.011,.007,
-.010939,.007695,
-.010759,.008368,
-.010464,.009,
-.010064,.009571,
-.009571,.010064,
-.009,.010464,
-.008368,.010759,
-.007695,.010939,
-.007,.011,
.007,.011,
.007695,.010939,
.008368,.010759,
.009,.010464,
.009571,.010064,
.010064,.009571,
.010464,.009,
.010759,.008368,
.010939,.007695,
.011,.007,
0.0*
%
%ADD16MACRO16*%
%AMMACRO23*
4,1,40,.013,-.017,
-.013,-.017,
-.013695,-.016939,
-.014368,-.016759,
-.015,-.016464,
-.015571,-.016064,
-.016064,-.015571,
-.016464,-.015,
-.016759,-.014368,
-.016939,-.013695,
-.017,-.013,
-.017,.013,
-.016939,.013695,
-.016759,.014368,
-.016464,.015,
-.016064,.015571,
-.015571,.016064,
-.015,.016464,
-.014368,.016759,
-.013695,.016939,
-.013,.017,
.013,.017,
.013695,.016939,
.014368,.016759,
.015,.016464,
.015571,.016064,
.016064,.015571,
.016464,.015,
.016759,.014368,
.016939,.013695,
.017,.013,
.017,-.013,
.016939,-.013695,
.016759,-.014368,
.016464,-.015,
.016064,-.015571,
.015571,-.016064,
.015,-.016464,
.014368,-.016759,
.013695,-.016939,
.013,-.017,
0.0*
%
%ADD23MACRO23*%
%AMMACRO34*
4,1,40,.012,.008,
.012,-.008,
.011939,-.008695,
.011759,-.009368,
.011464,-.01,
.011064,-.010571,
.010571,-.011064,
.01,-.011464,
.009368,-.011759,
.008695,-.011939,
.008,-.012,
-.008,-.012,
-.008695,-.011939,
-.009368,-.011759,
-.01,-.011464,
-.010571,-.011064,
-.011064,-.010571,
-.011464,-.01,
-.011759,-.009368,
-.011939,-.008695,
-.012,-.008,
-.012,.008,
-.011939,.008695,
-.011759,.009368,
-.011464,.01,
-.011064,.010571,
-.010571,.011064,
-.01,.011464,
-.009368,.011759,
-.008695,.011939,
-.008,.012,
.008,.012,
.008695,.011939,
.009368,.011759,
.01,.011464,
.010571,.011064,
.011064,.010571,
.011464,.01,
.011759,.009368,
.011939,.008695,
.012,.008,
0.0*
%
%ADD34MACRO34*%
%AMMACRO21*
4,1,40,-.007,.011,
.007,.011,
.007695,.010939,
.008368,.010759,
.009,.010464,
.009571,.010064,
.010064,.009571,
.010464,.009,
.010759,.008368,
.010939,.007695,
.011,.007,
.011,-.007,
.010939,-.007695,
.010759,-.008368,
.010464,-.009,
.010064,-.009571,
.009571,-.010064,
.009,-.010464,
.008368,-.010759,
.007695,-.010939,
.007,-.011,
-.007,-.011,
-.007695,-.010939,
-.008368,-.010759,
-.009,-.010464,
-.009571,-.010064,
-.010064,-.009571,
-.010464,-.009,
-.010759,-.008368,
-.010939,-.007695,
-.011,-.007,
-.011,.007,
-.010939,.007695,
-.010759,.008368,
-.010464,.009,
-.010064,.009571,
-.009571,.010064,
-.009,.010464,
-.008368,.010759,
-.007695,.010939,
-.007,.011,
0.0*
%
%ADD21MACRO21*%
%ADD40C,.02*%
%ADD41C,.006*%
G75*
%LPD*%
G75*
G54D10*
X26087Y-114844D03*
X26435Y373984D03*
X175335Y62719D03*
Y189062D03*
X547104Y69007D03*
Y195351D03*
X696192Y373984D03*
G54D20*
X123200Y293000D03*
X209200Y309500D03*
X248700Y156500D03*
Y152500D03*
X258200Y88500D03*
Y197000D03*
G54D11*
X25596Y316176D03*
X237013Y17712D03*
X287407Y345704D03*
G54D21*
X119800Y293000D03*
X205800Y309500D03*
X254800Y88500D03*
X245300Y156500D03*
Y152500D03*
X254800Y197000D03*
G54D30*
X255200Y164500D03*
G54D12*
X22401Y341025D03*
X291000Y22500D03*
X316610Y341025D03*
G54D40*
G01X-176139Y-183003D02*
G02I-12000J0D01*
G01X-181289D02*
G02I-6850J0D01*
G01X-172139D02*
X-204139D01*
G01X-188139Y-199003D02*
Y-167003D01*
G01X-172139Y-199003D02*
Y-279003D01*
G01D02*
X1178561D01*
G01X-172139Y-234503D02*
X1178561D01*
G01X-172139Y-199003D02*
X1178561D01*
G01X391061D02*
Y-279003D01*
G01X528561Y-199003D02*
Y-279003D01*
G01X643561Y-199003D02*
Y-279003D01*
G01X811061Y-199003D02*
Y-279003D01*
G01X981061Y-199003D02*
Y-279003D01*
G01X1178561Y-199003D02*
Y-279003D01*
G01X1210561Y-183003D02*
X1178561D01*
G01X1206561D02*
G02I-12000J0D01*
G01X1201411D02*
G02I-6850J0D01*
G01X1194561Y-199003D02*
Y-167003D01*
G54D22*
X155811Y305700D03*
Y313300D03*
G54D13*
X62500Y279500D03*
X67050Y338239D03*
X96400Y292250D03*
X100250Y324750D03*
X122500Y296600D03*
X112500Y302000D03*
X120750Y324544D03*
X107300Y317000D03*
X118500Y318500D03*
X111400Y311750D03*
X109500Y330500D03*
X119500Y330000D03*
X135000Y293000D03*
X136500Y311500D03*
X139500Y321000D03*
X125100Y340250D03*
X161311Y302000D03*
X165811Y308000D03*
X163500Y313300D03*
X181061Y302000D03*
X177811Y309500D03*
X173811Y324500D03*
Y315000D03*
X195561Y304250D03*
X202911Y296500D03*
X237500Y92000D03*
X239500Y43500D03*
X249000Y65000D03*
X252000Y82338D03*
X252500Y103000D03*
X249000Y132500D03*
X254500Y148500D03*
X255500Y153500D03*
X240500Y150000D03*
X240437Y161999D03*
X240300Y168500D03*
X252000Y191000D03*
X249000Y185000D03*
X252500Y211500D03*
X249000Y241000D03*
X244000Y277500D03*
X259500Y82338D03*
X257000Y92500D03*
X256500Y100000D03*
Y106000D03*
X267000Y131693D03*
X259500Y191000D03*
X256500Y208500D03*
Y201000D03*
Y214500D03*
X266500Y244000D03*
X263000Y318500D03*
X284000Y107392D03*
X274750Y140500D03*
X283000Y143000D03*
X284662Y170000D03*
X287500Y186500D03*
X276500Y197000D03*
X295311Y123500D03*
X290500Y139875D03*
X294000Y166500D03*
X316500Y249500D03*
Y320500D03*
G54D31*
X265551Y64724D03*
Y173386D03*
X311614Y31870D03*
G54D41*
G01X-148956Y-251503D02*
Y-269003D01*
X-140222D01*
G01X-127089Y-257337D02*
Y-269003D01*
G01Y-252670D02*
X-127526Y-252378D01*
Y-251795D01*
X-127089Y-251503D01*
X-126652Y-251795D01*
Y-252378D01*
X-127089Y-252670D01*
G01X-112646Y-273378D02*
X-111117Y-274545D01*
X-109371Y-274836D01*
X-107843Y-274545D01*
X-106532Y-273087D01*
X-105659Y-271045D01*
Y-257337D01*
G01Y-259670D02*
X-106532Y-258503D01*
X-107843Y-257628D01*
X-109371Y-257337D01*
X-111117Y-257920D01*
X-112209Y-259086D01*
X-113083Y-261128D01*
X-113519Y-263170D01*
X-113301Y-264920D01*
X-112427Y-266962D01*
X-111117Y-268420D01*
X-109371Y-269003D01*
X-108061Y-268711D01*
X-106532Y-267545D01*
X-105659Y-266379D01*
G01X-95801Y-269003D02*
Y-251503D01*
G01Y-259961D02*
X-94709Y-258503D01*
X-93617Y-257628D01*
X-91871Y-257337D01*
X-90561Y-257628D01*
X-89032Y-258795D01*
X-88377Y-260545D01*
Y-269003D01*
G01X-74589Y-251503D02*
Y-269003D01*
G01X-77646Y-257337D02*
X-71532D01*
G01X-60801Y-269003D02*
Y-257337D01*
G01Y-260253D02*
X-59927Y-258795D01*
X-58617Y-257628D01*
X-56871Y-257337D01*
X-55343Y-257628D01*
X-54032Y-258795D01*
X-53377Y-260836D01*
Y-269003D01*
G01X-39589Y-257337D02*
Y-269003D01*
G01Y-252670D02*
X-40026Y-252378D01*
Y-251795D01*
X-39589Y-251503D01*
X-39152Y-251795D01*
Y-252378D01*
X-39589Y-252670D01*
G01X-25801Y-269003D02*
Y-257337D01*
G01Y-260253D02*
X-24927Y-258795D01*
X-23617Y-257628D01*
X-21871Y-257337D01*
X-20343Y-257628D01*
X-19032Y-258795D01*
X-18377Y-260836D01*
Y-269003D01*
G01X-7646Y-273378D02*
X-6117Y-274545D01*
X-4371Y-274836D01*
X-2843Y-274545D01*
X-1532Y-273087D01*
X-659Y-271045D01*
Y-257337D01*
G01Y-259670D02*
X-1532Y-258503D01*
X-2843Y-257628D01*
X-4371Y-257337D01*
X-6117Y-257920D01*
X-7209Y-259086D01*
X-8083Y-261128D01*
X-8519Y-263170D01*
X-8301Y-264920D01*
X-7427Y-266962D01*
X-6117Y-268420D01*
X-4371Y-269003D01*
X-3061Y-268711D01*
X-1532Y-267545D01*
X-659Y-266379D01*
G01X26044Y-269003D02*
Y-251503D01*
X31284D01*
X33031Y-252378D01*
X34341Y-254420D01*
X34778Y-256753D01*
X34341Y-259086D01*
X33249Y-260836D01*
X31284Y-261712D01*
X26044D01*
G01X42452Y-251503D02*
X47911Y-269003D01*
X53370Y-251503D01*
G01X65411D02*
Y-269003D01*
G01X60389Y-251503D02*
X70433D01*
G01X94734Y-269003D02*
Y-251503D01*
X100411Y-266086D01*
X106088Y-251503D01*
Y-269003D01*
G01X117911Y-269586D02*
X117474Y-269295D01*
Y-268711D01*
X117911Y-268420D01*
X118348Y-268711D01*
Y-269295D01*
X117911Y-269586D01*
G01X131263Y-254420D02*
X132573Y-252670D01*
X134101Y-251795D01*
X135848Y-251503D01*
X138031Y-252086D01*
X139559Y-253545D01*
X139996Y-255294D01*
X139778Y-257045D01*
X138904Y-258503D01*
X134538Y-261420D01*
X132573Y-263461D01*
X131263Y-266379D01*
X130826Y-269003D01*
X139996D01*
G01X164952D02*
X170411Y-251503D01*
X175870Y-269003D01*
G01X173904Y-262878D02*
X166917D01*
G01X191841Y-251503D02*
Y-269003D01*
G01Y-266379D02*
X190968Y-267837D01*
X189657Y-268711D01*
X188129Y-269003D01*
X186383Y-268420D01*
X185073Y-266962D01*
X184199Y-265212D01*
X183981Y-263170D01*
X184199Y-261128D01*
X185073Y-259378D01*
X186383Y-257920D01*
X188129Y-257337D01*
X189657Y-257628D01*
X190749Y-258212D01*
X191841Y-259378D01*
G01X209341Y-269003D02*
Y-257337D01*
G01Y-259378D02*
X208468Y-258212D01*
X207157Y-257628D01*
X205629Y-257337D01*
X204101Y-257920D01*
X202791Y-259086D01*
X201917Y-260836D01*
X201481Y-263170D01*
X201917Y-265503D01*
X202791Y-267253D01*
X204101Y-268420D01*
X205629Y-269003D01*
X207157Y-268711D01*
X208468Y-267837D01*
X209341Y-266670D01*
G01X218981Y-274836D02*
Y-257337D01*
G01Y-259961D02*
X220073Y-258503D01*
X221164Y-257628D01*
X222911Y-257337D01*
X224439Y-257628D01*
X225968Y-259086D01*
X226623Y-261128D01*
X226841Y-263170D01*
X226623Y-265212D01*
X225968Y-267253D01*
X224657Y-268420D01*
X222911Y-269003D01*
X221383Y-268711D01*
X219854Y-267837D01*
X218981Y-266670D01*
G01X240411Y-251503D02*
Y-269003D01*
G01X237354Y-257337D02*
X243468D01*
G01X257911Y-269003D02*
X256601Y-268711D01*
X255291Y-267545D01*
X254417Y-265503D01*
X253981Y-263170D01*
X254417Y-260836D01*
X255291Y-258795D01*
X256601Y-257628D01*
X257911Y-257337D01*
X259221Y-257628D01*
X260531Y-258795D01*
X261404Y-260836D01*
X261623Y-263170D01*
X261404Y-265503D01*
X260531Y-267545D01*
X259221Y-268711D01*
X257911Y-269003D01*
G01X272354D02*
Y-257337D01*
G01Y-259670D02*
X273446Y-258503D01*
X274538Y-257628D01*
X276066Y-257337D01*
X277157Y-257628D01*
X278468Y-258503D01*
G01X315214Y-252962D02*
X313904Y-252086D01*
X312376Y-251503D01*
X310629D01*
X308664Y-252378D01*
X307136Y-253836D01*
X306044Y-255587D01*
X305171Y-258503D01*
X304952Y-261128D01*
X305389Y-263753D01*
X306044Y-265503D01*
X307354Y-267253D01*
X308883Y-268420D01*
X310411Y-269003D01*
X311939D01*
X313468Y-268420D01*
X314778Y-267545D01*
X315870Y-266379D01*
G01X331841Y-269003D02*
Y-257337D01*
G01Y-259378D02*
X330968Y-258212D01*
X329657Y-257628D01*
X328129Y-257337D01*
X326601Y-257920D01*
X325291Y-259086D01*
X324417Y-260836D01*
X323981Y-263170D01*
X324417Y-265503D01*
X325291Y-267253D01*
X326601Y-268420D01*
X328129Y-269003D01*
X329657Y-268711D01*
X330968Y-267837D01*
X331841Y-266670D01*
G01X342354Y-269003D02*
Y-257337D01*
G01Y-259670D02*
X343446Y-258503D01*
X344538Y-257628D01*
X346066Y-257337D01*
X347157Y-257628D01*
X348468Y-258503D01*
G01X366841Y-251503D02*
Y-269003D01*
G01Y-266379D02*
X365968Y-267837D01*
X364657Y-268711D01*
X363129Y-269003D01*
X361383Y-268420D01*
X360073Y-266962D01*
X359199Y-265212D01*
X358981Y-263170D01*
X359199Y-261128D01*
X360073Y-259378D01*
X361383Y-257920D01*
X363129Y-257337D01*
X364657Y-257628D01*
X365749Y-258212D01*
X366841Y-259378D01*
G01X68484Y-224003D02*
Y-206503D01*
X74161Y-221086D01*
X79838Y-206503D01*
Y-224003D01*
G01X91661D02*
X90351Y-223711D01*
X89041Y-222545D01*
X88167Y-220503D01*
X87731Y-218170D01*
X88167Y-215836D01*
X89041Y-213795D01*
X90351Y-212628D01*
X91661Y-212337D01*
X92971Y-212628D01*
X94281Y-213795D01*
X95154Y-215836D01*
X95373Y-218170D01*
X95154Y-220503D01*
X94281Y-222545D01*
X92971Y-223711D01*
X91661Y-224003D01*
G01X113091Y-206503D02*
Y-224003D01*
G01Y-221379D02*
X112218Y-222837D01*
X110907Y-223711D01*
X109379Y-224003D01*
X107633Y-223420D01*
X106323Y-221962D01*
X105449Y-220212D01*
X105231Y-218170D01*
X105449Y-216128D01*
X106323Y-214378D01*
X107633Y-212920D01*
X109379Y-212337D01*
X110907Y-212628D01*
X111999Y-213212D01*
X113091Y-214378D01*
G01X123386Y-216128D02*
X130373D01*
X129718Y-214086D01*
X128626Y-212920D01*
X127098Y-212337D01*
X125569Y-212628D01*
X124259Y-213503D01*
X123386Y-215545D01*
X122949Y-217295D01*
Y-219045D01*
X123386Y-220795D01*
X124478Y-222545D01*
X125788Y-223711D01*
X127316Y-224003D01*
X128844Y-223420D01*
X130373Y-221670D01*
G01X144161Y-224003D02*
Y-206503D01*
G01X424761Y-269003D02*
Y-251503D01*
X422141Y-255003D01*
G01Y-269003D02*
X427381D01*
G01X437458Y-266379D02*
X438767Y-267837D01*
X440296Y-268711D01*
X442261Y-269003D01*
X444226Y-268420D01*
X445754Y-267253D01*
X446846Y-265212D01*
X447064Y-262878D01*
X446628Y-260545D01*
X445536Y-259086D01*
X444007Y-257920D01*
X442479Y-257628D01*
X440951Y-257920D01*
X438986Y-259086D01*
X439641Y-251503D01*
X445536D01*
G01X459324Y-269003D02*
X459761Y-265212D01*
X460416Y-262003D01*
X461289Y-259086D01*
X462381Y-255878D01*
X464128Y-251503D01*
X455394D01*
G01X472458Y-266379D02*
X473767Y-267837D01*
X475296Y-268711D01*
X477261Y-269003D01*
X479226Y-268420D01*
X480754Y-267253D01*
X481846Y-265212D01*
X482064Y-262878D01*
X481628Y-260545D01*
X480536Y-259086D01*
X479007Y-257920D01*
X477479Y-257628D01*
X475951Y-257920D01*
X473986Y-259086D01*
X474641Y-251503D01*
X480536D01*
G01X494761D02*
X493014Y-252086D01*
X491704Y-253545D01*
X490831Y-255294D01*
X490176Y-257628D01*
X489958Y-260253D01*
X490176Y-262878D01*
X490831Y-265212D01*
X491704Y-266962D01*
X493014Y-268420D01*
X494761Y-269003D01*
X496507Y-268420D01*
X497818Y-266962D01*
X498691Y-265212D01*
X499346Y-262878D01*
X499564Y-260253D01*
X499346Y-257628D01*
X498691Y-255294D01*
X497818Y-253545D01*
X496507Y-252086D01*
X494761Y-251503D01*
G01X411644Y-224003D02*
Y-206503D01*
X416884D01*
X418631Y-207378D01*
X419941Y-209420D01*
X420378Y-211753D01*
X419941Y-214086D01*
X418849Y-215836D01*
X416884Y-216712D01*
X411644D01*
G01X438314Y-207962D02*
X437004Y-207086D01*
X435476Y-206503D01*
X433729D01*
X431764Y-207378D01*
X430236Y-208836D01*
X429144Y-210587D01*
X428271Y-213503D01*
X428052Y-216128D01*
X428489Y-218753D01*
X429144Y-220503D01*
X430454Y-222253D01*
X431983Y-223420D01*
X433511Y-224003D01*
X435039D01*
X436568Y-223420D01*
X437878Y-222545D01*
X438970Y-221379D01*
G01X452757Y-214670D02*
X453631Y-213795D01*
X454286Y-212337D01*
X454723Y-210294D01*
X454286Y-208545D01*
X453413Y-207378D01*
X451884Y-206503D01*
X445989D01*
Y-224003D01*
X453194D01*
X454723Y-222837D01*
X455596Y-221086D01*
X456033Y-219045D01*
X455596Y-217003D01*
X454286Y-215253D01*
X452757Y-214670D01*
X445989D01*
G01X461961Y-229836D02*
X475061D01*
G01X480989Y-224003D02*
Y-206503D01*
X491033Y-224003D01*
Y-206503D01*
G01X503511Y-224003D02*
X501764Y-223711D01*
X500236Y-222545D01*
X498926Y-220795D01*
X498052Y-218753D01*
X497616Y-216420D01*
Y-214086D01*
X498052Y-211753D01*
X498926Y-209711D01*
X500236Y-207962D01*
X501764Y-206795D01*
X503511Y-206503D01*
X505257Y-206795D01*
X506786Y-207962D01*
X508096Y-209711D01*
X508970Y-211753D01*
X509406Y-214086D01*
Y-216420D01*
X508970Y-218753D01*
X508096Y-220795D01*
X506786Y-222545D01*
X505257Y-223711D01*
X503511Y-224003D01*
G01X554352Y-206503D02*
X559811Y-224003D01*
X565270Y-206503D01*
G01X581678Y-224003D02*
X572944D01*
Y-206503D01*
X581678D01*
G01X578184Y-214961D02*
X572944D01*
G01X590444Y-224003D02*
Y-206503D01*
X595903D01*
X597649Y-207378D01*
X598741Y-208545D01*
X599178Y-210878D01*
X598741Y-213212D01*
X597431Y-214670D01*
X595903Y-215545D01*
X590444D01*
G01X595903D02*
X599178Y-224003D01*
G01X612311Y-224586D02*
X611874Y-224295D01*
Y-223711D01*
X612311Y-223420D01*
X612748Y-223711D01*
Y-224295D01*
X612311Y-224586D01*
G01X586061Y-269003D02*
Y-251503D01*
X583441Y-255003D01*
G01Y-269003D02*
X588681D01*
G01X760515Y-259670D02*
X759641Y-258795D01*
X758986Y-257337D01*
X758549Y-255294D01*
X758986Y-253545D01*
X759859Y-252378D01*
X761388Y-251503D01*
X767283D01*
Y-269003D01*
X760078D01*
X758549Y-267837D01*
X757676Y-266086D01*
X757239Y-264045D01*
X757676Y-262003D01*
X758986Y-260253D01*
X760515Y-259670D01*
X767283D01*
G01X750438Y-269003D02*
Y-251503D01*
X744761Y-266086D01*
X739084Y-251503D01*
Y-269003D01*
G01X732720D02*
X727261Y-251503D01*
X721802Y-269003D01*
G01X723768Y-262878D02*
X730755D01*
G01X714346Y-266670D02*
X712599Y-268128D01*
X710634Y-269003D01*
X708888D01*
X707141Y-268128D01*
X705831Y-266670D01*
X705176Y-264628D01*
X705613Y-262587D01*
X706704Y-260836D01*
X708669Y-259670D01*
X711289Y-259086D01*
X712818Y-257920D01*
X713473Y-255878D01*
X713036Y-253836D01*
X711944Y-252378D01*
X710416Y-251503D01*
X708888D01*
X707359Y-252086D01*
X706049Y-253545D01*
G01X697064Y-269003D02*
Y-251503D01*
G01X688768D02*
X697064Y-262295D01*
G01X687458Y-269003D02*
X693353Y-257337D01*
G01X687894Y-206503D02*
Y-224003D01*
X696628D01*
G01X713691D02*
Y-212337D01*
G01Y-214378D02*
X712818Y-213212D01*
X711507Y-212628D01*
X709979Y-212337D01*
X708451Y-212920D01*
X707141Y-214086D01*
X706267Y-215836D01*
X705831Y-218170D01*
X706267Y-220503D01*
X707141Y-222253D01*
X708451Y-223420D01*
X709979Y-224003D01*
X711507Y-223711D01*
X712818Y-222837D01*
X713691Y-221670D01*
G01X722676Y-229253D02*
X723986Y-229836D01*
X725733Y-229253D01*
X726824Y-228087D01*
X727698Y-226628D01*
X729007Y-221962D01*
X731846Y-212337D01*
G01X724859D02*
X729007Y-221962D01*
G01X741486Y-216128D02*
X748473D01*
X747818Y-214086D01*
X746726Y-212920D01*
X745198Y-212337D01*
X743669Y-212628D01*
X742359Y-213503D01*
X741486Y-215545D01*
X741049Y-217295D01*
Y-219045D01*
X741486Y-220795D01*
X742578Y-222545D01*
X743888Y-223711D01*
X745416Y-224003D01*
X746944Y-223420D01*
X748473Y-221670D01*
G01X759204Y-224003D02*
Y-212337D01*
G01Y-214670D02*
X760296Y-213503D01*
X761388Y-212628D01*
X762916Y-212337D01*
X764007Y-212628D01*
X765318Y-213503D01*
G01X830008Y-224003D02*
Y-206503D01*
X834374D01*
X836121Y-207378D01*
X837431Y-208545D01*
X838523Y-210294D01*
X839396Y-212337D01*
X839614Y-215253D01*
X839396Y-218170D01*
X838523Y-220212D01*
X837431Y-221962D01*
X836121Y-223128D01*
X834374Y-224003D01*
X830008D01*
G01X849036Y-216128D02*
X856023D01*
X855368Y-214086D01*
X854276Y-212920D01*
X852748Y-212337D01*
X851219Y-212628D01*
X849909Y-213503D01*
X849036Y-215545D01*
X848599Y-217295D01*
Y-219045D01*
X849036Y-220795D01*
X850128Y-222545D01*
X851438Y-223711D01*
X852966Y-224003D01*
X854494Y-223420D01*
X856023Y-221670D01*
G01X866536Y-221962D02*
X867628Y-223128D01*
X869156Y-224003D01*
X870466D01*
X871776Y-223420D01*
X872649Y-222545D01*
X873086Y-221379D01*
X872868Y-219628D01*
X871994Y-218753D01*
X868064Y-217003D01*
X867191Y-214961D01*
X867628Y-213503D01*
X868501Y-212628D01*
X869811Y-212337D01*
X871121Y-212628D01*
X872431Y-213503D01*
G01X887311Y-212337D02*
Y-224003D01*
G01Y-207670D02*
X886874Y-207378D01*
Y-206795D01*
X887311Y-206503D01*
X887748Y-206795D01*
Y-207378D01*
X887311Y-207670D01*
G01X901754Y-228378D02*
X903283Y-229545D01*
X905029Y-229836D01*
X906557Y-229545D01*
X907868Y-228087D01*
X908741Y-226045D01*
Y-212337D01*
G01Y-214670D02*
X907868Y-213503D01*
X906557Y-212628D01*
X905029Y-212337D01*
X903283Y-212920D01*
X902191Y-214086D01*
X901317Y-216128D01*
X900881Y-218170D01*
X901099Y-219920D01*
X901973Y-221962D01*
X903283Y-223420D01*
X905029Y-224003D01*
X906339Y-223711D01*
X907868Y-222545D01*
X908741Y-221379D01*
G01X918599Y-224003D02*
Y-212337D01*
G01Y-215253D02*
X919473Y-213795D01*
X920783Y-212628D01*
X922529Y-212337D01*
X924057Y-212628D01*
X925368Y-213795D01*
X926023Y-215836D01*
Y-224003D01*
G01X936536Y-216128D02*
X943523D01*
X942868Y-214086D01*
X941776Y-212920D01*
X940248Y-212337D01*
X938719Y-212628D01*
X937409Y-213503D01*
X936536Y-215545D01*
X936099Y-217295D01*
Y-219045D01*
X936536Y-220795D01*
X937628Y-222545D01*
X938938Y-223711D01*
X940466Y-224003D01*
X941994Y-223420D01*
X943523Y-221670D01*
G01X954254Y-224003D02*
Y-212337D01*
G01Y-214670D02*
X955346Y-213503D01*
X956438Y-212628D01*
X957966Y-212337D01*
X959057Y-212628D01*
X960368Y-213503D01*
G01X874194Y-265503D02*
X875286Y-267253D01*
X876596Y-268420D01*
X878124Y-269003D01*
X879871Y-268420D01*
X881181Y-267253D01*
X882491Y-265503D01*
X882928Y-263170D01*
Y-251503D01*
G01X896061Y-269003D02*
X894314Y-268711D01*
X892786Y-267545D01*
X891476Y-265795D01*
X890602Y-263753D01*
X890166Y-261420D01*
Y-259086D01*
X890602Y-256753D01*
X891476Y-254711D01*
X892786Y-252962D01*
X894314Y-251795D01*
X896061Y-251503D01*
X897807Y-251795D01*
X899336Y-252962D01*
X900646Y-254711D01*
X901520Y-256753D01*
X901956Y-259086D01*
Y-261420D01*
X901520Y-263753D01*
X900646Y-265795D01*
X899336Y-267545D01*
X897807Y-268711D01*
X896061Y-269003D01*
G01X913561D02*
Y-261128D01*
X909194Y-251503D01*
G01X917928D02*
X913561Y-261128D01*
G01X1001011Y-269003D02*
Y-251503D01*
X998391Y-255003D01*
G01Y-269003D02*
X1003631D01*
G01X1014363Y-254420D02*
X1015673Y-252670D01*
X1017201Y-251795D01*
X1018948Y-251503D01*
X1021131Y-252086D01*
X1022659Y-253545D01*
X1023096Y-255294D01*
X1022878Y-257045D01*
X1022004Y-258503D01*
X1017638Y-261420D01*
X1015673Y-263461D01*
X1014363Y-266379D01*
X1013926Y-269003D01*
X1023096D01*
G01X1032081Y-269586D02*
X1039941Y-251503D01*
G01X1048708Y-265503D02*
X1050017Y-267545D01*
X1051764Y-268711D01*
X1053729Y-269003D01*
X1055476Y-268711D01*
X1057223Y-267253D01*
X1058314Y-265503D01*
X1058533Y-263753D01*
X1058096Y-261712D01*
X1056568Y-260253D01*
X1055039Y-259670D01*
X1053074D01*
G01X1055039D02*
X1056349Y-258795D01*
X1057441Y-257337D01*
X1057878Y-255587D01*
X1057441Y-253836D01*
X1056349Y-252378D01*
X1054384Y-251503D01*
X1052419Y-251795D01*
X1050454Y-252962D01*
G01X1071011Y-251503D02*
X1069264Y-252086D01*
X1067954Y-253545D01*
X1067081Y-255294D01*
X1066426Y-257628D01*
X1066208Y-260253D01*
X1066426Y-262878D01*
X1067081Y-265212D01*
X1067954Y-266962D01*
X1069264Y-268420D01*
X1071011Y-269003D01*
X1072757Y-268420D01*
X1074068Y-266962D01*
X1074941Y-265212D01*
X1075596Y-262878D01*
X1075814Y-260253D01*
X1075596Y-257628D01*
X1074941Y-255294D01*
X1074068Y-253545D01*
X1072757Y-252086D01*
X1071011Y-251503D01*
G01X1084581Y-269586D02*
X1092441Y-251503D01*
G01X1101863Y-254420D02*
X1103173Y-252670D01*
X1104701Y-251795D01*
X1106448Y-251503D01*
X1108631Y-252086D01*
X1110159Y-253545D01*
X1110596Y-255294D01*
X1110378Y-257045D01*
X1109504Y-258503D01*
X1105138Y-261420D01*
X1103173Y-263461D01*
X1101863Y-266379D01*
X1101426Y-269003D01*
X1110596D01*
G01X1123511Y-251503D02*
X1121764Y-252086D01*
X1120454Y-253545D01*
X1119581Y-255294D01*
X1118926Y-257628D01*
X1118708Y-260253D01*
X1118926Y-262878D01*
X1119581Y-265212D01*
X1120454Y-266962D01*
X1121764Y-268420D01*
X1123511Y-269003D01*
X1125257Y-268420D01*
X1126568Y-266962D01*
X1127441Y-265212D01*
X1128096Y-262878D01*
X1128314Y-260253D01*
X1128096Y-257628D01*
X1127441Y-255294D01*
X1126568Y-253545D01*
X1125257Y-252086D01*
X1123511Y-251503D01*
G01X1141011Y-269003D02*
Y-251503D01*
X1138391Y-255003D01*
G01Y-269003D02*
X1143631D01*
G01X1154363Y-261712D02*
X1155891Y-259670D01*
X1157201Y-258503D01*
X1158948Y-257920D01*
X1160476Y-258503D01*
X1161568Y-259670D01*
X1162441Y-261420D01*
X1162659Y-263461D01*
X1162441Y-265212D01*
X1161568Y-266962D01*
X1160257Y-268420D01*
X1158729Y-269003D01*
X1156983Y-268420D01*
X1155454Y-266670D01*
X1154581Y-264045D01*
X1154363Y-261128D01*
X1154799Y-257337D01*
X1155454Y-255294D01*
X1156546Y-253253D01*
X1158074Y-251795D01*
X1159603Y-251503D01*
X1161131Y-252086D01*
X1162223Y-253545D01*
G01X1048708Y-224003D02*
Y-206503D01*
X1053074D01*
X1054821Y-207378D01*
X1056131Y-208545D01*
X1057223Y-210294D01*
X1058096Y-212337D01*
X1058314Y-215253D01*
X1058096Y-218170D01*
X1057223Y-220212D01*
X1056131Y-221962D01*
X1054821Y-223128D01*
X1053074Y-224003D01*
X1048708D01*
G01X1074941D02*
Y-212337D01*
G01Y-214378D02*
X1074068Y-213212D01*
X1072757Y-212628D01*
X1071229Y-212337D01*
X1069701Y-212920D01*
X1068391Y-214086D01*
X1067517Y-215836D01*
X1067081Y-218170D01*
X1067517Y-220503D01*
X1068391Y-222253D01*
X1069701Y-223420D01*
X1071229Y-224003D01*
X1072757Y-223711D01*
X1074068Y-222837D01*
X1074941Y-221670D01*
G01X1088511Y-206503D02*
Y-224003D01*
G01X1085454Y-212337D02*
X1091568D01*
G01X1102736Y-216128D02*
X1109723D01*
X1109068Y-214086D01*
X1107976Y-212920D01*
X1106448Y-212337D01*
X1104919Y-212628D01*
X1103609Y-213503D01*
X1102736Y-215545D01*
X1102299Y-217295D01*
Y-219045D01*
X1102736Y-220795D01*
X1103828Y-222545D01*
X1105138Y-223711D01*
X1106666Y-224003D01*
X1108194Y-223420D01*
X1109723Y-221670D01*
G54D23*
X143511Y313500D03*
X205011Y314000D03*
G54D14*
X99000Y284200D03*
X95000D03*
X110000D03*
X114000D03*
X117500Y341200D03*
X121500D03*
X168311Y301700D03*
X172311D03*
X176311D03*
X199811Y304200D03*
X233311Y152700D03*
X229311Y160200D03*
X233311Y167700D03*
X264500Y164700D03*
X266500Y240200D03*
X270500D03*
G54D32*
X265551Y143464D03*
Y252126D03*
G54D33*
X270940Y162250D03*
Y155750D03*
X273500Y162250D03*
X276060D03*
Y155750D03*
G54D15*
X99000Y280800D03*
X95000D03*
X110000D03*
X114000D03*
X117500Y337800D03*
X121500D03*
X168311Y298300D03*
X172311D03*
X176311D03*
X199811Y300800D03*
X233311Y149300D03*
X229311Y156800D03*
X233311Y164300D03*
X264500Y161300D03*
X266500Y236800D03*
X270500D03*
G54D24*
X149111Y313500D03*
X210611Y314000D03*
G54D34*
X258800Y164500D03*
G54D16*
X100000Y292300D03*
X100500Y302300D03*
X96500D03*
X104500D03*
X92500D03*
X119000Y308300D03*
X115000D03*
X109000Y337800D03*
X113500D03*
X218311Y304300D03*
X233311Y156800D03*
X229311Y149300D03*
Y164300D03*
X282500Y161300D03*
G54D25*
X222311Y307800D03*
X264500Y156800D03*
G54D26*
X222311Y304200D03*
X264500Y153200D03*
G54D35*
X302000Y290500D03*
Y300500D03*
Y310500D03*
G54D17*
X100000Y295700D03*
X100500Y305700D03*
X96500D03*
X104500D03*
X92500D03*
X119000Y311700D03*
X115000D03*
X109000Y341200D03*
X113500D03*
X218311Y307700D03*
X233311Y160200D03*
X229311Y152700D03*
Y167700D03*
X282500Y164700D03*
G54D36*
X320394Y46752D03*
Y49902D03*
Y53051D03*
Y56201D03*
Y59351D03*
Y62500D03*
Y65650D03*
Y68799D03*
Y71949D03*
Y75099D03*
Y78248D03*
Y81398D03*
Y84548D03*
Y87697D03*
Y90847D03*
Y93996D03*
Y97146D03*
Y100296D03*
Y103445D03*
Y106595D03*
Y109744D03*
Y112894D03*
Y116044D03*
Y119193D03*
Y122343D03*
Y125492D03*
Y128642D03*
X310118Y120670D03*
Y123820D03*
Y126969D03*
X320394Y131792D03*
Y134941D03*
Y138091D03*
Y141240D03*
Y144390D03*
X310118Y130119D03*
Y133268D03*
Y136418D03*
X320394Y147540D03*
Y150689D03*
Y153839D03*
Y156988D03*
Y160138D03*
Y163288D03*
Y166437D03*
Y169587D03*
G54D27*
X213800Y320000D03*
G54D18*
X96800Y317000D03*
Y321000D03*
X193611Y317000D03*
X254800Y96500D03*
Y205000D03*
X271300Y131500D03*
Y135500D03*
X255300Y160500D03*
G54D37*
X310315Y46142D03*
Y51142D03*
Y56142D03*
Y61142D03*
Y66142D03*
Y71142D03*
Y76142D03*
Y81142D03*
Y86142D03*
Y91142D03*
Y96142D03*
Y101142D03*
Y106142D03*
Y111142D03*
Y116142D03*
Y141142D03*
Y146142D03*
Y151142D03*
Y156142D03*
Y161142D03*
Y166142D03*
Y171142D03*
G54D28*
X208200Y320000D03*
G54D19*
X100200Y317000D03*
Y321000D03*
X197011Y317000D03*
X258200Y96500D03*
X258700Y160500D03*
X258200Y205000D03*
X274700Y131500D03*
Y135500D03*
G54D29*
X234700Y71000D03*
Y138500D03*
Y179500D03*
Y247000D03*
X242300Y71000D03*
Y138500D03*
Y179500D03*
Y247000D03*
G54D38*
X311614Y185414D03*
G54D39*
X334252Y13307D03*
Y203977D03*
M02*
